(kicad_pcb
	(version 20241229)
	(generator "pcbnew")
	(generator_version "9.0")
	(general
		(thickness 1.6)
		(legacy_teardrops no)
	)
	(paper "A4")
	(title_block
		(title "GMSL Deserializer")
		(date "2025-10-09")
		(rev "1.0.4")
		(company "Antmicro Ltd")
		(comment 1 "www.antmicro.com")
		(comment 9 "footprints 200-205 of 235")
	)
	(layers
		(0 "F.Cu" signal)
		(4 "In1.Cu" power)
		(6 "In2.Cu" power)
		(2 "B.Cu" signal)
		(9 "F.Adhes" user "F.Adhesive")
		(11 "B.Adhes" user "B.Adhesive")
		(13 "F.Paste" user)
		(15 "B.Paste" user)
		(5 "F.SilkS" user "F.Silkscreen")
		(7 "B.SilkS" user "B.Silkscreen")
		(1 "F.Mask" user)
		(3 "B.Mask" user)
		(17 "Dwgs.User" user "User.Drawings")
		(19 "Cmts.User" user "User.Comments")
		(21 "Eco1.User" user "User.Eco1")
		(23 "Eco2.User" user "User.Eco2")
		(25 "Edge.Cuts" user)
		(27 "Margin" user)
		(31 "F.CrtYd" user "F.Courtyard")
		(29 "B.CrtYd" user "B.Courtyard")
		(35 "F.Fab" user)
		(33 "B.Fab" user)
	)
	(footprint "antmicro-footprints:R_0402_1005Metric"
		(layer "B.Cu")
		(at 150.8809 96.375897 90)
		(descr "Resistor SMD 0402")
		(tags "resistor SMD 0402")
		(property "Reference" "R77"
			(at 5.750329 0.414422 90)
			(layer "B.SilkS")
			(effects
				(font
					(size 0.7 0.7)
					(thickness 0.15)
				)
				(justify right bottom mirror)
			)
		)
		(property "Value" "R_470R_0402"
			(at -1.011843 -1.772046 90)
			(layer "B.Fab")
			(effects
				(font
					(size 0.7 0.7)
					(thickness 0.15)
				)
				(justify right bottom mirror)
			)
		)
		(property "Datasheet" "https://www.bourns.com/docs/product-datasheets/cr.pdf"
			(at 0 0 90)
			(layer "F.Fab")
			(hide yes)
			(effects
				(font
					(size 1.27 1.27)
					(thickness 0.15)
				)
			)
		)
		(property "Description" "SMD Chip Resistor, 470 ohm, ± 1%, 62.5 mW, 0402 [1005 Metric], Thick Film, General Purpose"
			(at 0 0 90)
			(layer "F.Fab")
			(hide yes)
			(effects
				(font
					(size 1.27 1.27)
					(thickness 0.15)
				)
			)
		)
		(property "Author" "Antmicro"
			(at 325.845911 56.529026 135)
			(layer "B.Fab")
			(hide yes)
			(effects
				(font
					(size 1 1)
					(thickness 0.15)
				)
				(justify mirror)
			)
		)
		(property "License" "Apache-2.0"
			(at 325.845911 56.529026 135)
			(layer "B.Fab")
			(hide yes)
			(effects
				(font
					(size 1 1)
					(thickness 0.15)
				)
				(justify mirror)
			)
		)
		(property "MPN" "CR0402-FX-4700GLF"
			(at 325.845911 56.529026 135)
			(layer "B.Fab")
			(hide yes)
			(effects
				(font
					(size 1 1)
					(thickness 0.15)
				)
				(justify mirror)
			)
		)
		(property "Manufacturer" "Bourns"
			(at 325.845911 56.529026 135)
			(layer "B.Fab")
			(hide yes)
			(effects
				(font
					(size 1 1)
					(thickness 0.15)
				)
				(justify mirror)
			)
		)
		(property "Tolerance" "1%"
			(at 325.845911 56.529026 135)
			(layer "B.Fab")
			(hide yes)
			(effects
				(font
					(size 1 1)
					(thickness 0.15)
				)
				(justify mirror)
			)
		)
		(property "Val" "470R"
			(at 325.845911 56.529026 135)
			(layer "B.Fab")
			(hide yes)
			(effects
				(font
					(size 1 1)
					(thickness 0.15)
				)
				(justify mirror)
			)
		)
		(sheetname "/Power/")
		(sheetfile "power.kicad_sch")
		(attr smd)
		(fp_poly
			(pts
				(xy -0.925 0.47) (xy 0.925 0.47) (xy 0.925 -0.47) (xy -0.925 -0.47)
			)
			(stroke
				(width 0.05)
				(type default)
			)
			(fill no)
			(layer "B.CrtYd")
		)
		(fp_poly
			(pts
				(xy -0.5 0.25) (xy 0.5 0.25) (xy 0.5 -0.25) (xy -0.5 -0.25)
			)
			(stroke
				(width 0.15)
				(type solid)
			)
			(fill no)
			(layer "B.Fab")
		)
		(pad "1" smd roundrect
			(at -0.48 0 90)
			(size 0.59 0.64)
			(layers "B.Cu" "B.Mask" "B.Paste")
			(roundrect_rratio 0.25)
			(net 1 "GND")
			(pintype "passive")
		)
		(pad "2" smd roundrect
			(at 0.48 0 90)
			(size 0.59 0.64)
			(layers "B.Cu" "B.Mask" "B.Paste")
			(roundrect_rratio 0.25)
			(net 140 "Net-(D16-C)")
			(pintype "passive")
		)
	)
	(footprint "antmicro-footprints:C_0402_1005Metric"
		(layer "B.Cu")
		(at 140.252 83.996 45)
		(descr "Capacitor SMD 0402")
		(tags "capacitor SMD 0402")
		(property "Reference" "C53"
			(at -3.792854 -0.017147 45)
			(layer "B.SilkS")
			(effects
				(font
					(size 0.7 0.7)
					(thickness 0.15)
				)
				(justify right bottom mirror)
			)
		)
		(property "Value" "C_100n_0402"
			(at -1.022927 -2.155213 45)
			(layer "B.Fab")
			(effects
				(font
					(size 0.7 0.7)
					(thickness 0.15)
				)
				(justify right bottom mirror)
			)
		)
		(property "Datasheet" "https://www.murata.com/products/productdetail?partno=GRM155R61H104KE14%23"
			(at 0 0 45)
			(layer "F.Fab")
			(hide yes)
			(effects
				(font
					(size 1.27 1.27)
					(thickness 0.15)
				)
			)
		)
		(property "Description" "SMD Multilayer Ceramic Capacitor, 0.1 µF, 50 V, 0402 [1005 Metric], ± 10%, X5R, GRM Series"
			(at 0 0 45)
			(layer "F.Fab")
			(hide yes)
			(effects
				(font
					(size 1.27 1.27)
					(thickness 0.15)
				)
			)
		)
		(property "Author" "Antmicro"
			(at 100.40723 -74.772495 0)
			(layer "B.Fab")
			(hide yes)
			(effects
				(font
					(size 1 1)
					(thickness 0.15)
				)
				(justify mirror)
			)
		)
		(property "Dielectric" "X5R"
			(at 100.40723 -74.772495 0)
			(layer "B.Fab")
			(hide yes)
			(effects
				(font
					(size 1 1)
					(thickness 0.15)
				)
				(justify mirror)
			)
		)
		(property "License" "Apache-2.0"
			(at 100.40723 -74.772495 0)
			(layer "B.Fab")
			(hide yes)
			(effects
				(font
					(size 1 1)
					(thickness 0.15)
				)
				(justify mirror)
			)
		)
		(property "MPN" "GRM155R61H104KE14D"
			(at 100.40723 -74.772495 0)
			(layer "B.Fab")
			(hide yes)
			(effects
				(font
					(size 1 1)
					(thickness 0.15)
				)
				(justify mirror)
			)
		)
		(property "Manufacturer" "Murata"
			(at 100.40723 -74.772495 0)
			(layer "B.Fab")
			(hide yes)
			(effects
				(font
					(size 1 1)
					(thickness 0.15)
				)
				(justify mirror)
			)
		)
		(property "Val" "100n"
			(at 100.40723 -74.772495 0)
			(layer "B.Fab")
			(hide yes)
			(effects
				(font
					(size 1 1)
					(thickness 0.15)
				)
				(justify mirror)
			)
		)
		(property "Voltage" "50V"
			(at 100.40723 -74.772495 0)
			(layer "B.Fab")
			(hide yes)
			(effects
				(font
					(size 1 1)
					(thickness 0.15)
				)
				(justify mirror)
			)
		)
		(sheetname "/Deserializer/")
		(sheetfile "deserializer.kicad_sch")
		(attr smd)
		(fp_poly
			(pts
				(xy -0.925 0.47) (xy 0.925 0.47) (xy 0.925 -0.47) (xy -0.925 -0.47)
			)
			(stroke
				(width 0.05)
				(type default)
			)
			(fill no)
			(layer "B.CrtYd")
		)
		(fp_line
			(start -0.494 -0.248)
			(end 0.504 -0.248)
			(stroke
				(width 0.15)
				(type solid)
			)
			(layer "B.Fab")
		)
		(fp_line
			(start -0.494 0.25)
			(end -0.494 -0.248)
			(stroke
				(width 0.15)
				(type solid)
			)
			(layer "B.Fab")
		)
		(fp_line
			(start 0.504 -0.248)
			(end 0.504 0.25)
			(stroke
				(width 0.15)
				(type solid)
			)
			(layer "B.Fab")
		)
		(fp_line
			(start 0.504 0.25)
			(end -0.494 0.25)
			(stroke
				(width 0.15)
				(type solid)
			)
			(layer "B.Fab")
		)
		(pad "1" smd roundrect
			(at -0.48 0 45)
			(size 0.59 0.64)
			(layers "B.Cu" "B.Mask" "B.Paste")
			(roundrect_rratio 0.25)
			(net 1 "GND")
			(pintype "passive")
		)
		(pad "2" smd roundrect
			(at 0.48 0 45)
			(size 0.59 0.64)
			(layers "B.Cu" "B.Mask" "B.Paste")
			(roundrect_rratio 0.25)
			(net 29 "/Deserializer/VTERM")
			(pintype "passive")
		)
	)
	(footprint "antmicro-footprints:TP_SMD_0.75mm"
		(layer "B.Cu")
		(at 146.304 97.89 180)
		(property "Reference" "TP16"
			(at 0 0.6 0)
			(layer "B.SilkS")
			(hide yes)
			(effects
				(font
					(size 0.7 0.7)
					(thickness 0.15)
				)
				(justify left bottom mirror)
			)
		)
		(property "Value" "TP_0.75mm_SMD"
			(at 0 -1.2 0)
			(layer "B.Fab")
			(effects
				(font
					(size 0.7 0.7)
					(thickness 0.15)
				)
				(justify left bottom mirror)
			)
		)
		(property "Description" "SMT test point"
			(at 0 0 0)
			(layer "B.Fab")
			(hide yes)
			(effects
				(font
					(size 1.27 1.27)
					(thickness 0.15)
				)
				(justify mirror)
			)
		)
		(property "MPN" ""
			(at 0 0 0)
			(unlocked yes)
			(layer "B.Fab")
			(hide yes)
			(effects
				(font
					(size 1 1)
					(thickness 0.15)
				)
				(justify mirror)
			)
		)
		(property "Manufacturer" ""
			(at 0 0 0)
			(unlocked yes)
			(layer "B.Fab")
			(hide yes)
			(effects
				(font
					(size 1 1)
					(thickness 0.15)
				)
				(justify mirror)
			)
		)
		(property "Author" "Antmicro"
			(at 0 0 0)
			(unlocked yes)
			(layer "B.Fab")
			(hide yes)
			(effects
				(font
					(size 1 1)
					(thickness 0.15)
				)
				(justify mirror)
			)
		)
		(property "License" "Apache-2.0"
			(at 0 0 0)
			(unlocked yes)
			(layer "B.Fab")
			(hide yes)
			(effects
				(font
					(size 1 1)
					(thickness 0.15)
				)
				(justify mirror)
			)
		)
		(sheetname "/Power/")
		(sheetfile "power.kicad_sch")
		(attr exclude_from_pos_files)
		(fp_circle
			(center 0 0)
			(end 0.475 0)
			(stroke
				(width 0.05)
				(type default)
			)
			(fill no)
			(layer "B.CrtYd")
		)
		(fp_text user "License: Apache-2.0"
			(at -0.4 -5.101 0)
			(layer "B.Fab")
			(effects
				(font
					(size 0.7 0.7)
					(thickness 0.15)
				)
				(justify left bottom mirror)
			)
		)
		(fp_text user "Author: Antmicro"
			(at -0.4 -3.901 0)
			(layer "B.Fab")
			(effects
				(font
					(size 0.7 0.7)
					(thickness 0.15)
				)
				(justify left bottom mirror)
			)
		)
		(fp_text user "${REFERENCE}"
			(at -0.4 -2.7 0)
			(layer "B.Fab")
			(effects
				(font
					(size 0.7 0.7)
					(thickness 0.15)
				)
				(justify left bottom mirror)
			)
		)
		(pad "1" smd circle
			(at 0 0 180)
			(size 0.75 0.75)
			(layers "B.Cu" "B.Mask")
			(net 11 "/Power/OUT_1V2")
			(pinfunction "1")
			(pintype "passive")
		)
	)
	(footprint "antmicro-footprints:C_0402_1005Metric"
		(layer "B.Cu")
		(at 149.098 76.2 -135)
		(descr "Capacitor SMD 0402")
		(tags "capacitor SMD 0402")
		(property "Reference" "C47"
			(at -3.681905 -0.449013 45)
			(layer "B.SilkS")
			(effects
				(font
					(size 0.7 0.7)
					(thickness 0.15)
				)
				(justify left bottom mirror)
			)
		)
		(property "Value" "C_100n_0402"
			(at -1.022927 -2.155213 45)
			(layer "B.Fab")
			(effects
				(font
					(size 0.7 0.7)
					(thickness 0.15)
				)
				(justify left bottom mirror)
			)
		)
		(property "Datasheet" "https://www.murata.com/products/productdetail?partno=GRM155R61H104KE14%23"
			(at 0 0 225)
			(layer "F.Fab")
			(hide yes)
			(effects
				(font
					(size 1.27 1.27)
					(thickness 0.15)
				)
			)
		)
		(property "Description" "SMD Multilayer Ceramic Capacitor, 0.1 µF, 50 V, 0402 [1005 Metric], ± 10%, X5R, GRM Series"
			(at 0 0 225)
			(layer "F.Fab")
			(hide yes)
			(effects
				(font
					(size 1.27 1.27)
					(thickness 0.15)
				)
			)
		)
		(property "Author" "Antmicro"
			(at 200.64467 235.509744 0)
			(layer "B.Fab")
			(hide yes)
			(effects
				(font
					(size 1 1)
					(thickness 0.15)
				)
				(justify mirror)
			)
		)
		(property "Dielectric" "X5R"
			(at 200.64467 235.509744 0)
			(layer "B.Fab")
			(hide yes)
			(effects
				(font
					(size 1 1)
					(thickness 0.15)
				)
				(justify mirror)
			)
		)
		(property "License" "Apache-2.0"
			(at 200.64467 235.509744 0)
			(layer "B.Fab")
			(hide yes)
			(effects
				(font
					(size 1 1)
					(thickness 0.15)
				)
				(justify mirror)
			)
		)
		(property "MPN" "GRM155R61H104KE14D"
			(at 200.64467 235.509744 0)
			(layer "B.Fab")
			(hide yes)
			(effects
				(font
					(size 1 1)
					(thickness 0.15)
				)
				(justify mirror)
			)
		)
		(property "Manufacturer" "Murata"
			(at 200.64467 235.509744 0)
			(layer "B.Fab")
			(hide yes)
			(effects
				(font
					(size 1 1)
					(thickness 0.15)
				)
				(justify mirror)
			)
		)
		(property "Val" "100n"
			(at 200.64467 235.509744 0)
			(layer "B.Fab")
			(hide yes)
			(effects
				(font
					(size 1 1)
					(thickness 0.15)
				)
				(justify mirror)
			)
		)
		(property "Voltage" "50V"
			(at 200.64467 235.509744 0)
			(layer "B.Fab")
			(hide yes)
			(effects
				(font
					(size 1 1)
					(thickness 0.15)
				)
				(justify mirror)
			)
		)
		(sheetname "/Deserializer/")
		(sheetfile "deserializer.kicad_sch")
		(attr smd)
		(fp_poly
			(pts
				(xy -0.925 0.47) (xy 0.925 0.47) (xy 0.925 -0.47) (xy -0.925 -0.47)
			)
			(stroke
				(width 0.05)
				(type default)
			)
			(fill no)
			(layer "B.CrtYd")
		)
		(fp_line
			(start 0.504 0.25)
			(end -0.494 0.25)
			(stroke
				(width 0.15)
				(type solid)
			)
			(layer "B.Fab")
		)
		(fp_line
			(start 0.504 -0.248)
			(end 0.504 0.25)
			(stroke
				(width 0.15)
				(type solid)
			)
			(layer "B.Fab")
		)
		(fp_line
			(start -0.494 0.25)
			(end -0.494 -0.248)
			(stroke
				(width 0.15)
				(type solid)
			)
			(layer "B.Fab")
		)
		(fp_line
			(start -0.494 -0.248)
			(end 0.504 -0.248)
			(stroke
				(width 0.15)
				(type solid)
			)
			(layer "B.Fab")
		)
		(pad "1" smd roundrect
			(at -0.48 0 225)
			(size 0.59 0.64)
			(layers "B.Cu" "B.Mask" "B.Paste")
			(roundrect_rratio 0.25)
			(net 1 "GND")
			(pintype "passive")
		)
		(pad "2" smd roundrect
			(at 0.48 0 225)
			(size 0.59 0.64)
			(layers "B.Cu" "B.Mask" "B.Paste")
			(roundrect_rratio 0.25)
			(net 28 "/Deserializer/CAP_VDD")
			(pintype "passive")
		)
	)
	(footprint "antmicro-footprints:R_0402_1005Metric"
		(layer "B.Cu")
		(at 136.55 89.45 -90)
		(descr "Resistor SMD 0402")
		(tags "resistor SMD 0402")
		(property "Reference" "R74"
			(at 0.85 -0.45 90)
			(layer "B.SilkS")
			(effects
				(font
					(size 0.7 0.7)
					(thickness 0.15)
				)
				(justify left bottom mirror)
			)
		)
		(property "Value" "R_100k_0402"
			(at -1.011843 -1.772047 90)
			(layer "B.Fab")
			(effects
				(font
					(size 0.7 0.7)
					(thickness 0.15)
				)
				(justify left bottom mirror)
			)
		)
		(property "Datasheet" "https://www.bourns.com/docs/product-datasheets/cr.pdf"
			(at 0 0 270)
			(layer "F.Fab")
			(hide yes)
			(effects
				(font
					(size 1.27 1.27)
					(thickness 0.15)
				)
			)
		)
		(property "Description" "SMD Chip Resistor, 100 kohm, ± 1%, 62.5 mW, 0402 [1005 Metric], Thick Film, General Purpose"
			(at 0 0 270)
			(layer "F.Fab")
			(hide yes)
			(effects
				(font
					(size 1.27 1.27)
					(thickness 0.15)
				)
			)
		)
		(property "Author" "Antmicro"
			(at 47.1 226 0)
			(layer "B.Fab")
			(hide yes)
			(effects
				(font
					(size 1 1)
					(thickness 0.15)
				)
				(justify mirror)
			)
		)
		(property "License" "Apache-2.0"
			(at 47.1 226 0)
			(layer "B.Fab")
			(hide yes)
			(effects
				(font
					(size 1 1)
					(thickness 0.15)
				)
				(justify mirror)
			)
		)
		(property "MPN" "CR0402-FX-1003GLF"
			(at 47.1 226 0)
			(layer "B.Fab")
			(hide yes)
			(effects
				(font
					(size 1 1)
					(thickness 0.15)
				)
				(justify mirror)
			)
		)
		(property "Manufacturer" "Bourns"
			(at 47.1 226 0)
			(layer "B.Fab")
			(hide yes)
			(effects
				(font
					(size 1 1)
					(thickness 0.15)
				)
				(justify mirror)
			)
		)
		(property "Tolerance" "1%"
			(at 47.1 226 0)
			(layer "B.Fab")
			(hide yes)
			(effects
				(font
					(size 1 1)
					(thickness 0.15)
				)
				(justify mirror)
			)
		)
		(property "Val" "100k"
			(at 47.1 226 0)
			(layer "B.Fab")
			(hide yes)
			(effects
				(font
					(size 1 1)
					(thickness 0.15)
				)
				(justify mirror)
			)
		)
		(sheetname "/Power/")
		(sheetfile "power.kicad_sch")
		(attr smd)
		(fp_rect
			(start -0.925 0.47)
			(end 0.925 -0.47)
			(stroke
				(width 0.05)
				(type default)
			)
			(fill no)
			(layer "B.CrtYd")
		)
		(fp_rect
			(start -0.5 0.25)
			(end 0.5 -0.25)
			(stroke
				(width 0.15)
				(type solid)
			)
			(fill no)
			(layer "B.Fab")
		)
		(pad "1" smd roundrect
			(at -0.48 0 270)
			(size 0.59 0.64)
			(layers "B.Cu" "B.Mask" "B.Paste")
			(roundrect_rratio 0.25)
			(net 1 "GND")
			(pintype "passive")
		)
		(pad "2" smd roundrect
			(at 0.48 0 270)
			(size 0.59 0.64)
			(layers "B.Cu" "B.Mask" "B.Paste")
			(roundrect_rratio 0.25)
			(net 10 "/Power/OUT_1V8")
			(pintype "passive")
		)
	)
	(footprint "antmicro-footprints:SOT-523"
		(layer "B.Cu")
		(at 134.9 89.65)
		(property "Reference" "Q4"
			(at -0.8 2.05 0)
			(layer "B.SilkS")
			(effects
				(font
					(size 0.7 0.7)
					(thickness 0.15)
				)
				(justify right bottom mirror)
			)
		)
		(property "Value" "DMG1012T-7"
			(at 0.1 -1.824 0)
			(layer "B.Fab")
			(effects
				(font
					(size 0.7 0.7)
					(thickness 0.15)
				)
				(justify right bottom mirror)
			)
		)
		(property "Datasheet" "https://www.diodes.com/assets/Datasheets/ds31783.pdf"
			(at 0 0 0)
			(layer "F.Fab")
			(hide yes)
			(effects
				(font
					(size 1.27 1.27)
					(thickness 0.15)
				)
			)
		)
		(property "Description" "Power MOSFET, N Channel, 20 V, 630 mA, 0.3 ohm, SOT-523, Surface Mount"
			(at 0 0 0)
			(layer "F.Fab")
			(hide yes)
			(effects
				(font
					(size 1.27 1.27)
					(thickness 0.15)
				)
			)
		)
		(property "Author" "Antmicro"
			(at 0 0 0)
			(layer "B.Fab")
			(hide yes)
			(effects
				(font
					(size 1 1)
					(thickness 0.15)
				)
				(justify mirror)
			)
		)
		(property "License" "Apache-2.0"
			(at 0 0 0)
			(layer "B.Fab")
			(hide yes)
			(effects
				(font
					(size 1 1)
					(thickness 0.15)
				)
				(justify mirror)
			)
		)
		(property "MPN" "DMG1012T-7"
			(at 0 0 0)
			(layer "B.Fab")
			(hide yes)
			(effects
				(font
					(size 1 1)
					(thickness 0.15)
				)
				(justify mirror)
			)
		)
		(property "Manufacturer" "Diodes Incorporated"
			(at 0 0 0)
			(layer "B.Fab")
			(hide yes)
			(effects
				(font
					(size 1 1)
					(thickness 0.15)
				)
				(justify mirror)
			)
		)
		(property "Public" ""
			(at 0 0 0)
			(layer "B.Fab")
			(hide yes)
			(effects
				(font
					(size 1 1)
					(thickness 0.15)
				)
				(justify mirror)
			)
		)
		(sheetname "/Power/")
		(sheetfile "power.kicad_sch")
		(attr smd)
		(fp_line
			(start -0.927 0.351)
			(end -0.927 0.051)
			(stroke
				(width 0.15)
				(type solid)
			)
			(layer "B.SilkS")
		)
		(fp_line
			(start -0.725 0.551)
			(end -0.927 0.351)
			(stroke
				(width 0.15)
				(type solid)
			)
			(layer "B.SilkS")
		)
		(fp_line
			(start -0.277 0.551)
			(end -0.725 0.551)
			(stroke
				(width 0.15)
				(type solid)
			)
			(layer "B.SilkS")
		)
		(fp_line
			(start -0.277 0.75)
			(end -0.277 0.551)
			(stroke
				(width 0.15)
				(type solid)
			)
			(layer "B.SilkS")
		)
		(fp_circle
			(center -0.9652 -0.9652)
			(end -0.9152 -0.9652)
			(stroke
				(width 0.15)
				(type solid)
			)
			(fill yes)
			(layer "B.SilkS")
		)
		(fp_line
			(start -1.12 -1.15)
			(end -1.12 1.16)
			(stroke
				(width 0.05)
				(type solid)
			)
			(layer "B.CrtYd")
		)
		(fp_line
			(start 1.1 -1.15)
			(end -1.12 -1.15)
			(stroke
				(width 0.05)
				(type solid)
			)
			(layer "B.CrtYd")
		)
		(fp_line
			(start 1.1 -1.15)
			(end 1.1 1.16)
			(stroke
				(width 0.05)
				(type solid)
			)
			(layer "B.CrtYd")
		)
		(fp_line
			(start 1.1 1.16)
			(end -1.12 1.16)
			(stroke
				(width 0.05)
				(type solid)
			)
			(layer "B.CrtYd")
		)
		(fp_line
			(start -0.802 -0.424)
			(end -0.802 0.276)
			(stroke
				(width 0.15)
				(type solid)
			)
			(layer "B.Fab")
		)
		(fp_line
			(start -0.802 -0.424)
			(end 0.8 -0.424)
			(stroke
				(width 0.15)
				(type solid)
			)
			(layer "B.Fab")
		)
		(fp_line
			(start -0.802 0.276)
			(end -0.652 0.425)
			(stroke
				(width 0.15)
				(type solid)
			)
			(layer "B.Fab")
		)
		(fp_line
			(start -0.652 0.425)
			(end 0.8 0.425)
			(stroke
				(width 0.15)
				(type solid)
			)
			(layer "B.Fab")
		)
		(fp_line
			(start 0.8 -0.424)
			(end 0.8 0.425)
			(stroke
				(width 0.15)
				(type solid)
			)
			(layer "B.Fab")
		)
		(fp_circle
			(center -0.9652 -0.9652)
			(end -0.9144 -0.9652)
			(stroke
				(width 0.15)
				(type solid)
			)
			(fill no)
			(layer "B.Fab")
		)
		(pad "1" smd rect
			(at -0.5 -0.65)
			(size 0.4 0.51)
			(layers "B.Cu" "B.Mask" "B.Paste")
			(net 11 "/Power/OUT_1V2")
			(pinfunction "G")
			(pintype "input")
		)
		(pad "2" smd rect
			(at 0.498 -0.65)
			(size 0.4 0.51)
			(layers "B.Cu" "B.Mask" "B.Paste")
			(net 1 "GND")
			(pinfunction "S")
			(pintype "passive")
		)
		(pad "3" smd rect
			(at 0 0.652)
			(size 0.4 0.51)
			(layers "B.Cu" "B.Mask" "B.Paste")
			(net 143 "Net-(D19-C)")
			(pinfunction "D")
			(pintype "passive")
		)
	)
)
